FILE_TYPE = MACRO_DRAWING;
SET COLOR_WIRE YELLOW;
SET COLOR_PROP ORANGE;
SET COLOR_DOT WHITE;
SET COLOR_ARC YELLOW;
SET COLOR_BODY GREEN;
SET COLOR_NOTE PURPLE;
SET PROP_DISPLAY VALUE;
SET PAGE_NUMBER P196;
FORCEADD OFFPAGE..1
(-1525 -7775);
FORCEPROP 2 LAST $XR0 206 
J 0
(-1777 -7775);
DISPLAY 0.638298 (-1777 -7775);
PAINT MONO (-1777 -7775);
FORCEPROP 2 LAST CDS_LIB standard
J 0
(-1525 -7775);
DISPLAY INVISIBLE (-1525 -7775);
FORCEPROP 1 LAST OFFPAGE TRUE
J 0
(-1200 -7900);
DISPLAY 0.872340 (-1200 -7900);
DISPLAY INVISIBLE (-1200 -7900);
FORCEPROP 1 LAST COMMENT_BODY TRUE
J 0
(-1400 -7875);
DISPLAY 0.872340 (-1400 -7875);
PAINT GREEN (-1400 -7875);
DISPLAY INVISIBLE (-1400 -7875);
FORCEPROP 2 LAST PATH I1
J 0
(-1775 -7725);
DISPLAY 1.021277 (-1775 -7725);
DISPLAY INVISIBLE (-1775 -7725);
FORCEADD Q_RES..1
(-100 -7775);
FORCEPROP 1 LAST PART_NUMBER CS02202FB02
J 0
(25 -7725);
DISPLAY 0.638298 (25 -7725);
DISPLAY INVISIBLE (25 -7725);
FORCEPROP 1 LAST MATERIAL CHIP
J 0
(25 -7675);
DISPLAY 0.638298 (25 -7675);
FORCEPROP 1 LAST VALUE 22
J 2
(175 -7775);
DISPLAY 0.787234 (175 -7775);
FORCEPROP 1 LAST TOLERANCE 1%
J 0
(200 -7775);
DISPLAY 0.787234 (200 -7775);
FORCEPROP 1 LAST WATTAGE 1/16W
J 2
(375 -7675);
DISPLAY 0.638298 (375 -7675);
FORCEPROP 1 LAST PACK_TYPE 0402LF
J 0
(300 -7775);
DISPLAY 0.787234 (300 -7775);
FORCEPROP 1 LAST $LOCATION R3201
J 0
(-350 -7775);
DISPLAY 0.808511 (-350 -7775);
FORCEPROP 1 LASTPIN (-200 -7775) $PN 1
J 0
(-188 -7763);
DISPLAY 0.787234 (-188 -7763);
FORCEPROP 1 LASTPIN (0 -7775) $PN 2
J 0
(-38 -7763);
DISPLAY 0.787234 (-38 -7763);
FORCEPROP 2 LAST CDS_LIB pure_quanta
J 0
(-100 -7775);
PAINT MONO (-100 -7775);
DISPLAY INVISIBLE (-100 -7775);
FORCEPROP 1 LAST PATH I10
J 0
(-150 -7625);
DISPLAY 0.978723 (-150 -7625);
PAINT WHITE (-150 -7625);
DISPLAY INVISIBLE (-150 -7625);
FORCEPROP 2 LAST CDS_LOCATION R3201
J 0
(-150 -7575);
DISPLAY 1.021277 (-150 -7575);
DISPLAY INVISIBLE (-150 -7575);
FORCEPROP 2 LAST $SEC 1
J 0
(-150 -7575);
DISPLAY 0.680851 (-150 -7575);
PAINT MONO (-150 -7575);
DISPLAY INVISIBLE (-150 -7575);
FORCEPROP 2 LAST CDS_SEC 1
J 0
(-150 -7575);
DISPLAY 1.021277 (-150 -7575);
DISPLAY INVISIBLE (-150 -7575);
FORCEADD Q_RES..1
(-100 -7625);
FORCEPROP 1 LAST PART_NUMBER CS02202FB02
J 0
(25 -7575);
DISPLAY 0.638298 (25 -7575);
DISPLAY INVISIBLE (25 -7575);
FORCEPROP 1 LAST MATERIAL CHIP
J 0
(25 -7525);
DISPLAY 0.638298 (25 -7525);
FORCEPROP 1 LAST TOLERANCE 1%
J 0
(200 -7625);
DISPLAY 0.787234 (200 -7625);
FORCEPROP 1 LAST WATTAGE 1/16W
J 2
(375 -7525);
DISPLAY 0.638298 (375 -7525);
FORCEPROP 1 LAST PACK_TYPE 0402LF
J 0
(300 -7625);
DISPLAY 0.787234 (300 -7625);
FORCEPROP 1 LAST VALUE 22
J 2
(175 -7625);
DISPLAY 0.787234 (175 -7625);
FORCEPROP 1 LAST $LOCATION R3200
J 0
(-350 -7625);
DISPLAY 0.808511 (-350 -7625);
FORCEPROP 1 LASTPIN (-200 -7625) $PN 1
J 0
(-188 -7613);
DISPLAY 0.787234 (-188 -7613);
FORCEPROP 1 LASTPIN (0 -7625) $PN 2
J 0
(-38 -7613);
DISPLAY 0.787234 (-38 -7613);
FORCEPROP 2 LAST CDS_LIB pure_quanta
J 0
(-100 -7625);
PAINT MONO (-100 -7625);
DISPLAY INVISIBLE (-100 -7625);
FORCEPROP 1 LAST PATH I11
J 0
(-150 -7475);
DISPLAY 0.978723 (-150 -7475);
PAINT WHITE (-150 -7475);
DISPLAY INVISIBLE (-150 -7475);
FORCEPROP 2 LAST CDS_LOCATION R3200
J 0
(-150 -7425);
DISPLAY 1.021277 (-150 -7425);
DISPLAY INVISIBLE (-150 -7425);
FORCEPROP 2 LAST $SEC 1
J 0
(-150 -7425);
DISPLAY 0.680851 (-150 -7425);
PAINT MONO (-150 -7425);
DISPLAY INVISIBLE (-150 -7425);
FORCEPROP 2 LAST CDS_SEC 1
J 0
(-150 -7425);
DISPLAY 1.021277 (-150 -7425);
DISPLAY INVISIBLE (-150 -7425);
FORCEADD Q_RES..1
(-100 -7375);
FORCEPROP 1 LAST PART_NUMBER CS02202FB02
J 0
(25 -7325);
DISPLAY 0.638298 (25 -7325);
DISPLAY INVISIBLE (25 -7325);
FORCEPROP 1 LAST MATERIAL CHIP
J 0
(25 -7275);
DISPLAY 0.638298 (25 -7275);
FORCEPROP 1 LAST VALUE 22
J 2
(175 -7375);
DISPLAY 0.787234 (175 -7375);
FORCEPROP 1 LAST TOLERANCE 1%
J 0
(200 -7375);
DISPLAY 0.787234 (200 -7375);
FORCEPROP 1 LAST WATTAGE 1/16W
J 2
(375 -7275);
DISPLAY 0.638298 (375 -7275);
FORCEPROP 1 LAST PACK_TYPE 0402LF
J 0
(300 -7375);
DISPLAY 0.787234 (300 -7375);
FORCEPROP 1 LAST $LOCATION R3199
J 0
(-350 -7375);
DISPLAY 0.808511 (-350 -7375);
FORCEPROP 1 LASTPIN (-200 -7375) $PN 1
J 0
(-188 -7363);
DISPLAY 0.787234 (-188 -7363);
FORCEPROP 1 LASTPIN (0 -7375) $PN 2
J 0
(-38 -7363);
DISPLAY 0.787234 (-38 -7363);
FORCEPROP 2 LAST CDS_LIB pure_quanta
J 0
(-100 -7375);
PAINT MONO (-100 -7375);
DISPLAY INVISIBLE (-100 -7375);
FORCEPROP 1 LAST PATH I12
J 0
(-150 -7225);
DISPLAY 0.978723 (-150 -7225);
PAINT WHITE (-150 -7225);
DISPLAY INVISIBLE (-150 -7225);
FORCEPROP 2 LAST CDS_LOCATION R3199
J 0
(-150 -7175);
DISPLAY 1.021277 (-150 -7175);
DISPLAY INVISIBLE (-150 -7175);
FORCEPROP 2 LAST $SEC 1
J 0
(-150 -7175);
DISPLAY 0.680851 (-150 -7175);
PAINT MONO (-150 -7175);
DISPLAY INVISIBLE (-150 -7175);
FORCEPROP 2 LAST CDS_SEC 1
J 0
(-150 -7175);
DISPLAY 1.021277 (-150 -7175);
DISPLAY INVISIBLE (-150 -7175);
FORCEADD Q_RES..1
(-100 -7225);
FORCEPROP 1 LAST PART_NUMBER CS02202FB02
J 0
(25 -7175);
DISPLAY 0.638298 (25 -7175);
DISPLAY INVISIBLE (25 -7175);
FORCEPROP 1 LAST PACK_TYPE 0402LF
J 0
(300 -7225);
DISPLAY 0.787234 (300 -7225);
FORCEPROP 1 LAST WATTAGE 1/16W
J 2
(375 -7125);
DISPLAY 0.638298 (375 -7125);
FORCEPROP 1 LAST MATERIAL CHIP
J 0
(25 -7125);
DISPLAY 0.638298 (25 -7125);
FORCEPROP 1 LAST VALUE 22
J 2
(175 -7225);
DISPLAY 0.787234 (175 -7225);
FORCEPROP 1 LAST TOLERANCE 1%
J 0
(200 -7225);
DISPLAY 0.787234 (200 -7225);
FORCEPROP 1 LAST $LOCATION R3198
J 0
(-350 -7225);
DISPLAY 0.808511 (-350 -7225);
FORCEPROP 1 LASTPIN (-200 -7225) $PN 1
J 0
(-188 -7213);
DISPLAY 0.787234 (-188 -7213);
FORCEPROP 1 LASTPIN (0 -7225) $PN 2
J 0
(-38 -7213);
DISPLAY 0.787234 (-38 -7213);
FORCEPROP 2 LAST CDS_LIB pure_quanta
J 0
(-100 -7225);
PAINT MONO (-100 -7225);
DISPLAY INVISIBLE (-100 -7225);
FORCEPROP 1 LAST PATH I13
J 0
(-150 -7075);
DISPLAY 0.978723 (-150 -7075);
PAINT WHITE (-150 -7075);
DISPLAY INVISIBLE (-150 -7075);
FORCEPROP 2 LAST CDS_LOCATION R3198
J 0
(-150 -7025);
DISPLAY 1.021277 (-150 -7025);
DISPLAY INVISIBLE (-150 -7025);
FORCEPROP 2 LAST $SEC 1
J 0
(-150 -7025);
DISPLAY 0.680851 (-150 -7025);
PAINT MONO (-150 -7025);
DISPLAY INVISIBLE (-150 -7025);
FORCEPROP 2 LAST CDS_SEC 1
J 0
(-150 -7025);
DISPLAY 1.021277 (-150 -7025);
DISPLAY INVISIBLE (-150 -7025);
FORCEADD Q_RES..1
(-100 -6975);
FORCEPROP 1 LAST PART_NUMBER CS02202FB02
J 0
(25 -6925);
DISPLAY 0.638298 (25 -6925);
DISPLAY INVISIBLE (25 -6925);
FORCEPROP 1 LAST PACK_TYPE 0402LF
J 0
(300 -6975);
DISPLAY 0.787234 (300 -6975);
FORCEPROP 1 LAST TOLERANCE 1%
J 0
(200 -6975);
DISPLAY 0.787234 (200 -6975);
FORCEPROP 1 LAST VALUE 22
J 2
(175 -6975);
DISPLAY 0.787234 (175 -6975);
FORCEPROP 1 LAST MATERIAL CHIP
J 0
(25 -6875);
DISPLAY 0.638298 (25 -6875);
FORCEPROP 1 LAST WATTAGE 1/16W
J 2
(375 -6875);
DISPLAY 0.638298 (375 -6875);
FORCEPROP 1 LAST $LOCATION R3197
J 0
(-350 -6975);
DISPLAY 0.808511 (-350 -6975);
FORCEPROP 1 LASTPIN (-200 -6975) $PN 1
J 0
(-188 -6963);
DISPLAY 0.787234 (-188 -6963);
FORCEPROP 1 LASTPIN (0 -6975) $PN 2
J 0
(-38 -6963);
DISPLAY 0.787234 (-38 -6963);
FORCEPROP 2 LAST CDS_LIB pure_quanta
J 0
(-100 -6975);
PAINT MONO (-100 -6975);
DISPLAY INVISIBLE (-100 -6975);
FORCEPROP 1 LAST PATH I14
J 0
(-150 -6825);
DISPLAY 0.978723 (-150 -6825);
PAINT WHITE (-150 -6825);
DISPLAY INVISIBLE (-150 -6825);
FORCEPROP 2 LAST CDS_LOCATION R3197
J 0
(-150 -6775);
DISPLAY 1.021277 (-150 -6775);
DISPLAY INVISIBLE (-150 -6775);
FORCEPROP 2 LAST $SEC 1
J 0
(-150 -6775);
DISPLAY 0.680851 (-150 -6775);
PAINT MONO (-150 -6775);
DISPLAY INVISIBLE (-150 -6775);
FORCEPROP 2 LAST CDS_SEC 1
J 0
(-150 -6775);
DISPLAY 1.021277 (-150 -6775);
DISPLAY INVISIBLE (-150 -6775);
FORCEADD Q_RES..1
(-100 -6825);
FORCEPROP 1 LAST PART_NUMBER CS02202FB02
J 0
(25 -6775);
DISPLAY 0.638298 (25 -6775);
DISPLAY INVISIBLE (25 -6775);
FORCEPROP 1 LAST PACK_TYPE 0402LF
J 0
(300 -6825);
DISPLAY 0.787234 (300 -6825);
FORCEPROP 1 LAST WATTAGE 1/16W
J 2
(375 -6725);
DISPLAY 0.638298 (375 -6725);
FORCEPROP 1 LAST VALUE 22
J 2
(175 -6825);
DISPLAY 0.787234 (175 -6825);
FORCEPROP 1 LAST TOLERANCE 1%
J 0
(200 -6825);
DISPLAY 0.787234 (200 -6825);
FORCEPROP 1 LAST MATERIAL CHIP
J 0
(25 -6725);
DISPLAY 0.638298 (25 -6725);
FORCEPROP 1 LAST $LOCATION R3196
J 0
(-350 -6825);
DISPLAY 0.808511 (-350 -6825);
FORCEPROP 1 LASTPIN (-200 -6825) $PN 1
J 0
(-188 -6813);
DISPLAY 0.787234 (-188 -6813);
FORCEPROP 1 LASTPIN (0 -6825) $PN 2
J 0
(-38 -6813);
DISPLAY 0.787234 (-38 -6813);
FORCEPROP 2 LAST CDS_LIB pure_quanta
J 0
(-100 -6825);
PAINT MONO (-100 -6825);
DISPLAY INVISIBLE (-100 -6825);
FORCEPROP 1 LAST PATH I15
J 0
(-150 -6675);
DISPLAY 0.978723 (-150 -6675);
PAINT WHITE (-150 -6675);
DISPLAY INVISIBLE (-150 -6675);
FORCEPROP 2 LAST CDS_LOCATION R3196
J 0
(-150 -6625);
DISPLAY 1.021277 (-150 -6625);
DISPLAY INVISIBLE (-150 -6625);
FORCEPROP 2 LAST $SEC 1
J 0
(-150 -6625);
DISPLAY 0.680851 (-150 -6625);
PAINT MONO (-150 -6625);
DISPLAY INVISIBLE (-150 -6625);
FORCEPROP 2 LAST CDS_SEC 1
J 0
(-150 -6625);
DISPLAY 1.021277 (-150 -6625);
DISPLAY INVISIBLE (-150 -6625);
FORCEADD Q_RES..1
(-100 -6575);
FORCEPROP 1 LAST PART_NUMBER CS02202FB02
J 0
(25 -6525);
DISPLAY 0.638298 (25 -6525);
DISPLAY INVISIBLE (25 -6525);
FORCEPROP 1 LAST WATTAGE 1/16W
J 2
(375 -6475);
DISPLAY 0.638298 (375 -6475);
FORCEPROP 1 LAST PACK_TYPE 0402LF
J 0
(300 -6575);
DISPLAY 0.787234 (300 -6575);
FORCEPROP 1 LAST VALUE 22
J 2
(175 -6575);
DISPLAY 0.787234 (175 -6575);
FORCEPROP 1 LAST TOLERANCE 1%
J 0
(200 -6575);
DISPLAY 0.787234 (200 -6575);
FORCEPROP 1 LAST MATERIAL CHIP
J 0
(25 -6475);
DISPLAY 0.638298 (25 -6475);
FORCEPROP 1 LAST $LOCATION R3195
J 0
(-350 -6575);
DISPLAY 0.808511 (-350 -6575);
FORCEPROP 1 LASTPIN (-200 -6575) $PN 1
J 0
(-188 -6563);
DISPLAY 0.787234 (-188 -6563);
FORCEPROP 1 LASTPIN (0 -6575) $PN 2
J 0
(-38 -6563);
DISPLAY 0.787234 (-38 -6563);
FORCEPROP 2 LAST CDS_LIB pure_quanta
J 0
(-100 -6575);
PAINT MONO (-100 -6575);
DISPLAY INVISIBLE (-100 -6575);
FORCEPROP 1 LAST PATH I16
J 0
(-150 -6425);
DISPLAY 0.978723 (-150 -6425);
PAINT WHITE (-150 -6425);
DISPLAY INVISIBLE (-150 -6425);
FORCEPROP 2 LAST CDS_LOCATION R3195
J 0
(-150 -6375);
DISPLAY 1.021277 (-150 -6375);
DISPLAY INVISIBLE (-150 -6375);
FORCEPROP 2 LAST $SEC 1
J 0
(-150 -6375);
DISPLAY 0.680851 (-150 -6375);
PAINT MONO (-150 -6375);
DISPLAY INVISIBLE (-150 -6375);
FORCEPROP 2 LAST CDS_SEC 1
J 0
(-150 -6375);
DISPLAY 1.021277 (-150 -6375);
DISPLAY INVISIBLE (-150 -6375);
FORCEADD Q_RES..1
(-100 -6425);
FORCEPROP 1 LAST PART_NUMBER CS02202FB02
J 0
(25 -6375);
DISPLAY 0.638298 (25 -6375);
DISPLAY INVISIBLE (25 -6375);
FORCEPROP 1 LAST WATTAGE 1/16W
J 2
(375 -6325);
DISPLAY 0.638298 (375 -6325);
FORCEPROP 1 LAST PACK_TYPE 0402LF
J 0
(300 -6425);
DISPLAY 0.787234 (300 -6425);
FORCEPROP 1 LAST TOLERANCE 1%
J 0
(200 -6425);
DISPLAY 0.787234 (200 -6425);
FORCEPROP 1 LAST MATERIAL CHIP
J 0
(25 -6325);
DISPLAY 0.638298 (25 -6325);
FORCEPROP 1 LAST VALUE 22
J 2
(175 -6425);
DISPLAY 0.787234 (175 -6425);
FORCEPROP 1 LAST $LOCATION R3194
J 0
(-350 -6425);
DISPLAY 0.808511 (-350 -6425);
FORCEPROP 1 LASTPIN (-200 -6425) $PN 1
J 0
(-188 -6413);
DISPLAY 0.787234 (-188 -6413);
FORCEPROP 1 LASTPIN (0 -6425) $PN 2
J 0
(-38 -6413);
DISPLAY 0.787234 (-38 -6413);
FORCEPROP 2 LAST CDS_LIB pure_quanta
J 0
(-100 -6425);
PAINT MONO (-100 -6425);
DISPLAY INVISIBLE (-100 -6425);
FORCEPROP 1 LAST PATH I17
J 0
(-150 -6275);
DISPLAY 0.978723 (-150 -6275);
PAINT WHITE (-150 -6275);
DISPLAY INVISIBLE (-150 -6275);
FORCEPROP 2 LAST CDS_LOCATION R3194
J 0
(-150 -6225);
DISPLAY 1.021277 (-150 -6225);
DISPLAY INVISIBLE (-150 -6225);
FORCEPROP 2 LAST $SEC 1
J 0
(-150 -6225);
DISPLAY 0.680851 (-150 -6225);
PAINT MONO (-150 -6225);
DISPLAY INVISIBLE (-150 -6225);
FORCEPROP 2 LAST CDS_SEC 1
J 0
(-150 -6225);
DISPLAY 1.021277 (-150 -6225);
DISPLAY INVISIBLE (-150 -6225);
FORCEADD Q_RES..1
(-150 -3875);
FORCEPROP 1 LAST PART_NUMBER CS00002JB13
J 0
(-25 -3825);
DISPLAY 0.638298 (-25 -3825);
DISPLAY INVISIBLE (-25 -3825);
FORCEPROP 1 LAST WATTAGE 1/16W
J 2
(325 -3775);
DISPLAY 0.638298 (325 -3775);
FORCEPROP 1 LAST PACK_TYPE 0402LF
J 0
(250 -3875);
DISPLAY 0.787234 (250 -3875);
FORCEPROP 1 LAST TOLERANCE 5%
J 0
(150 -3875);
DISPLAY 0.787234 (150 -3875);
FORCEPROP 1 LAST VALUE 0
J 2
(125 -3875);
DISPLAY 0.787234 (125 -3875);
FORCEPROP 1 LAST MATERIAL CHIP
J 0
(-25 -3775);
DISPLAY 0.638298 (-25 -3775);
FORCEPROP 1 LAST $LOCATION R3355
J 0
(-400 -3875);
DISPLAY 0.808511 (-400 -3875);
FORCEPROP 1 LASTPIN (-250 -3875) $PN 1
J 0
(-238 -3863);
DISPLAY 0.787234 (-238 -3863);
FORCEPROP 1 LASTPIN (-50 -3875) $PN 2
J 0
(-88 -3863);
DISPLAY 0.787234 (-88 -3863);
FORCEPROP 2 LAST CDS_LIB pure_quanta
J 0
(-150 -3875);
PAINT MONO (-150 -3875);
DISPLAY INVISIBLE (-150 -3875);
FORCEPROP 1 LAST PATH I18
J 0
(-200 -3725);
DISPLAY 0.978723 (-200 -3725);
PAINT WHITE (-200 -3725);
DISPLAY INVISIBLE (-200 -3725);
FORCEPROP 2 LAST CDS_LOCATION R3355
J 0
(-200 -3675);
DISPLAY 1.021277 (-200 -3675);
DISPLAY INVISIBLE (-200 -3675);
FORCEPROP 2 LAST $SEC 1
J 0
(-200 -3675);
DISPLAY 0.680851 (-200 -3675);
PAINT MONO (-200 -3675);
DISPLAY INVISIBLE (-200 -3675);
FORCEPROP 2 LAST CDS_SEC 1
J 0
(-200 -3675);
DISPLAY 1.021277 (-200 -3675);
DISPLAY INVISIBLE (-200 -3675);
FORCEADD OFFPAGE..1
(-1575 -3725);
FORCEPROP 2 LAST $XR0 211 
J 0
(-1827 -3725);
DISPLAY 0.638298 (-1827 -3725);
PAINT MONO (-1827 -3725);
FORCEPROP 1 LAST COMMENT_BODY TRUE
J 0
(-1450 -3825);
DISPLAY 0.872340 (-1450 -3825);
PAINT GREEN (-1450 -3825);
DISPLAY INVISIBLE (-1450 -3825);
FORCEPROP 1 LAST OFFPAGE TRUE
J 0
(-1250 -3850);
DISPLAY 0.872340 (-1250 -3850);
DISPLAY INVISIBLE (-1250 -3850);
FORCEPROP 2 LAST CDS_LIB standard
J 0
(-1575 -3725);
DISPLAY INVISIBLE (-1575 -3725);
FORCEPROP 2 LAST PATH I19
J 0
(-1825 -3675);
DISPLAY 1.021277 (-1825 -3675);
DISPLAY INVISIBLE (-1825 -3675);
FORCEADD OFFPAGE..1
(-1525 -7625);
FORCEPROP 2 LAST $XR0 206 
J 0
(-1777 -7625);
DISPLAY 0.638298 (-1777 -7625);
PAINT MONO (-1777 -7625);
FORCEPROP 2 LAST CDS_LIB standard
J 0
(-1525 -7625);
DISPLAY INVISIBLE (-1525 -7625);
FORCEPROP 1 LAST OFFPAGE TRUE
J 0
(-1200 -7750);
DISPLAY 0.872340 (-1200 -7750);
DISPLAY INVISIBLE (-1200 -7750);
FORCEPROP 1 LAST COMMENT_BODY TRUE
J 0
(-1400 -7725);
DISPLAY 0.872340 (-1400 -7725);
PAINT GREEN (-1400 -7725);
DISPLAY INVISIBLE (-1400 -7725);
FORCEPROP 2 LAST PATH I2
J 0
(-1775 -7575);
DISPLAY 1.021277 (-1775 -7575);
DISPLAY INVISIBLE (-1775 -7575);
FORCEADD OFFPAGE..1
(-1575 -3500);
FORCEPROP 2 LAST $XR0 211 
J 0
(-1827 -3500);
DISPLAY 0.638298 (-1827 -3500);
PAINT MONO (-1827 -3500);
FORCEPROP 2 LAST CDS_LIB standard
J 0
(-1575 -3500);
DISPLAY INVISIBLE (-1575 -3500);
FORCEPROP 1 LAST OFFPAGE TRUE
J 0
(-1250 -3625);
DISPLAY 0.872340 (-1250 -3625);
DISPLAY INVISIBLE (-1250 -3625);
FORCEPROP 1 LAST COMMENT_BODY TRUE
J 0
(-1450 -3600);
DISPLAY 0.872340 (-1450 -3600);
PAINT GREEN (-1450 -3600);
DISPLAY INVISIBLE (-1450 -3600);
FORCEPROP 2 LAST PATH I20
J 0
(-1825 -3450);
DISPLAY 1.021277 (-1825 -3450);
DISPLAY INVISIBLE (-1825 -3450);
FORCEADD OFFPAGE..1
(-1575 -3350);
FORCEPROP 2 LAST $XR0 211 
J 0
(-1827 -3350);
DISPLAY 0.638298 (-1827 -3350);
PAINT MONO (-1827 -3350);
FORCEPROP 2 LAST CDS_LIB standard
J 0
(-1575 -3350);
DISPLAY INVISIBLE (-1575 -3350);
FORCEPROP 1 LAST OFFPAGE TRUE
J 0
(-1250 -3475);
DISPLAY 0.872340 (-1250 -3475);
DISPLAY INVISIBLE (-1250 -3475);
FORCEPROP 1 LAST COMMENT_BODY TRUE
J 0
(-1450 -3450);
DISPLAY 0.872340 (-1450 -3450);
PAINT GREEN (-1450 -3450);
DISPLAY INVISIBLE (-1450 -3450);
FORCEPROP 2 LAST PATH I21
J 0
(-1825 -3300);
DISPLAY 1.021277 (-1825 -3300);
DISPLAY INVISIBLE (-1825 -3300);
FORCEADD OFFPAGE..1
(-1550 -3025);
FORCEPROP 2 LAST $XR0 211 
J 0
(-1802 -3025);
DISPLAY 0.638298 (-1802 -3025);
PAINT MONO (-1802 -3025);
FORCEPROP 2 LAST CDS_LIB standard
J 0
(-1550 -3025);
DISPLAY INVISIBLE (-1550 -3025);
FORCEPROP 1 LAST OFFPAGE TRUE
J 0
(-1225 -3150);
DISPLAY 0.872340 (-1225 -3150);
DISPLAY INVISIBLE (-1225 -3150);
FORCEPROP 1 LAST COMMENT_BODY TRUE
J 0
(-1425 -3125);
DISPLAY 0.872340 (-1425 -3125);
PAINT GREEN (-1425 -3125);
DISPLAY INVISIBLE (-1425 -3125);
FORCEPROP 2 LAST PATH I22
J 0
(-1800 -2975);
DISPLAY 1.021277 (-1800 -2975);
DISPLAY INVISIBLE (-1800 -2975);
FORCEADD OFFPAGE..1
(-1550 -2875);
FORCEPROP 2 LAST $XR0 211 
J 0
(-1802 -2875);
DISPLAY 0.638298 (-1802 -2875);
PAINT MONO (-1802 -2875);
FORCEPROP 2 LAST CDS_LIB standard
J 0
(-1550 -2875);
DISPLAY INVISIBLE (-1550 -2875);
FORCEPROP 1 LAST OFFPAGE TRUE
J 0
(-1225 -3000);
DISPLAY 0.872340 (-1225 -3000);
DISPLAY INVISIBLE (-1225 -3000);
FORCEPROP 1 LAST COMMENT_BODY TRUE
J 0
(-1425 -2975);
DISPLAY 0.872340 (-1425 -2975);
PAINT GREEN (-1425 -2975);
DISPLAY INVISIBLE (-1425 -2975);
FORCEPROP 2 LAST PATH I23
J 0
(-1800 -2825);
DISPLAY 1.021277 (-1800 -2825);
DISPLAY INVISIBLE (-1800 -2825);
FORCEADD Q_RES..1
(-150 -3725);
FORCEPROP 1 LAST PART_NUMBER CS00002JB13
J 0
(-25 -3675);
DISPLAY 0.638298 (-25 -3675);
DISPLAY INVISIBLE (-25 -3675);
FORCEPROP 1 LAST PACK_TYPE 0402LF
J 0
(250 -3725);
DISPLAY 0.787234 (250 -3725);
FORCEPROP 1 LAST VALUE 0
J 2
(125 -3725);
DISPLAY 0.787234 (125 -3725);
FORCEPROP 1 LAST TOLERANCE 5%
J 0
(150 -3725);
DISPLAY 0.787234 (150 -3725);
FORCEPROP 1 LAST WATTAGE 1/16W
J 2
(325 -3625);
DISPLAY 0.638298 (325 -3625);
FORCEPROP 1 LAST MATERIAL CHIP
J 0
(-25 -3625);
DISPLAY 0.638298 (-25 -3625);
FORCEPROP 1 LAST $LOCATION R3354
J 0
(-400 -3725);
DISPLAY 0.808511 (-400 -3725);
FORCEPROP 1 LASTPIN (-250 -3725) $PN 1
J 0
(-238 -3713);
DISPLAY 0.787234 (-238 -3713);
FORCEPROP 1 LASTPIN (-50 -3725) $PN 2
J 0
(-88 -3713);
DISPLAY 0.787234 (-88 -3713);
FORCEPROP 2 LAST CDS_LIB pure_quanta
J 0
(-150 -3725);
PAINT MONO (-150 -3725);
DISPLAY INVISIBLE (-150 -3725);
FORCEPROP 1 LAST PATH I24
J 0
(-200 -3575);
DISPLAY 0.978723 (-200 -3575);
PAINT WHITE (-200 -3575);
DISPLAY INVISIBLE (-200 -3575);
FORCEPROP 2 LAST CDS_LOCATION R3354
J 0
(-200 -3525);
DISPLAY 1.021277 (-200 -3525);
DISPLAY INVISIBLE (-200 -3525);
FORCEPROP 2 LAST $SEC 1
J 0
(-200 -3525);
DISPLAY 0.680851 (-200 -3525);
PAINT MONO (-200 -3525);
DISPLAY INVISIBLE (-200 -3525);
FORCEPROP 2 LAST CDS_SEC 1
J 0
(-200 -3525);
DISPLAY 1.021277 (-200 -3525);
DISPLAY INVISIBLE (-200 -3525);
FORCEADD Q_RES..1
(-150 -3500);
FORCEPROP 1 LAST PART_NUMBER CS00002JB13
J 0
(-25 -3450);
DISPLAY 0.638298 (-25 -3450);
DISPLAY INVISIBLE (-25 -3450);
FORCEPROP 1 LAST WATTAGE 1/16W
J 2
(325 -3400);
DISPLAY 0.638298 (325 -3400);
FORCEPROP 1 LAST MATERIAL CHIP
J 0
(-25 -3400);
DISPLAY 0.638298 (-25 -3400);
FORCEPROP 1 LAST PACK_TYPE 0402LF
J 0
(250 -3500);
DISPLAY 0.787234 (250 -3500);
FORCEPROP 1 LAST VALUE 0
J 2
(125 -3500);
DISPLAY 0.787234 (125 -3500);
FORCEPROP 1 LAST TOLERANCE 5%
J 0
(150 -3500);
DISPLAY 0.787234 (150 -3500);
FORCEPROP 1 LAST $LOCATION R3353
J 0
(-400 -3500);
DISPLAY 0.808511 (-400 -3500);
FORCEPROP 1 LASTPIN (-250 -3500) $PN 1
J 0
(-238 -3488);
DISPLAY 0.787234 (-238 -3488);
FORCEPROP 1 LASTPIN (-50 -3500) $PN 2
J 0
(-88 -3488);
DISPLAY 0.787234 (-88 -3488);
FORCEPROP 2 LAST CDS_LIB pure_quanta
J 0
(-150 -3500);
PAINT MONO (-150 -3500);
DISPLAY INVISIBLE (-150 -3500);
FORCEPROP 1 LAST PATH I25
J 0
(-200 -3350);
DISPLAY 0.978723 (-200 -3350);
PAINT WHITE (-200 -3350);
DISPLAY INVISIBLE (-200 -3350);
FORCEPROP 2 LAST CDS_LOCATION R3353
J 0
(-200 -3300);
DISPLAY 1.021277 (-200 -3300);
DISPLAY INVISIBLE (-200 -3300);
FORCEPROP 2 LAST $SEC 1
J 0
(-200 -3300);
DISPLAY 0.680851 (-200 -3300);
PAINT MONO (-200 -3300);
DISPLAY INVISIBLE (-200 -3300);
FORCEPROP 2 LAST CDS_SEC 1
J 0
(-200 -3300);
DISPLAY 1.021277 (-200 -3300);
DISPLAY INVISIBLE (-200 -3300);
FORCEADD Q_RES..1
(-150 -3350);
FORCEPROP 1 LAST PART_NUMBER CS00002JB13
J 0
(-25 -3300);
DISPLAY 0.638298 (-25 -3300);
DISPLAY INVISIBLE (-25 -3300);
FORCEPROP 1 LAST TOLERANCE 5%
J 0
(150 -3350);
DISPLAY 0.787234 (150 -3350);
FORCEPROP 1 LAST PACK_TYPE 0402LF
J 0
(250 -3350);
DISPLAY 0.787234 (250 -3350);
FORCEPROP 1 LAST WATTAGE 1/16W
J 2
(325 -3250);
DISPLAY 0.638298 (325 -3250);
FORCEPROP 1 LAST VALUE 0
J 2
(125 -3350);
DISPLAY 0.787234 (125 -3350);
FORCEPROP 1 LAST MATERIAL CHIP
J 0
(-25 -3250);
DISPLAY 0.638298 (-25 -3250);
FORCEPROP 1 LAST $LOCATION R3352
J 0
(-400 -3350);
DISPLAY 0.808511 (-400 -3350);
FORCEPROP 1 LASTPIN (-250 -3350) $PN 1
J 0
(-238 -3338);
DISPLAY 0.787234 (-238 -3338);
FORCEPROP 1 LASTPIN (-50 -3350) $PN 2
J 0
(-88 -3338);
DISPLAY 0.787234 (-88 -3338);
FORCEPROP 2 LAST CDS_LIB pure_quanta
J 0
(-150 -3350);
PAINT MONO (-150 -3350);
DISPLAY INVISIBLE (-150 -3350);
FORCEPROP 1 LAST PATH I26
J 0
(-200 -3200);
DISPLAY 0.978723 (-200 -3200);
PAINT WHITE (-200 -3200);
DISPLAY INVISIBLE (-200 -3200);
FORCEPROP 2 LAST CDS_LOCATION R3352
J 0
(-200 -3150);
DISPLAY 1.021277 (-200 -3150);
DISPLAY INVISIBLE (-200 -3150);
FORCEPROP 2 LAST $SEC 1
J 0
(-200 -3150);
DISPLAY 0.680851 (-200 -3150);
PAINT MONO (-200 -3150);
DISPLAY INVISIBLE (-200 -3150);
FORCEPROP 2 LAST CDS_SEC 1
J 0
(-200 -3150);
DISPLAY 1.021277 (-200 -3150);
DISPLAY INVISIBLE (-200 -3150);
FORCEADD Q_RES..1
(-125 -2875);
FORCEPROP 1 LAST PART_NUMBER CS00002JB13
J 0
(0 -2825);
DISPLAY 0.638298 (0 -2825);
DISPLAY INVISIBLE (0 -2825);
FORCEPROP 1 LAST TOLERANCE 5%
J 0
(175 -2875);
DISPLAY 0.787234 (175 -2875);
FORCEPROP 1 LAST MATERIAL CHIP
J 0
(0 -2775);
DISPLAY 0.638298 (0 -2775);
FORCEPROP 1 LAST PACK_TYPE 0402LF
J 0
(275 -2875);
DISPLAY 0.787234 (275 -2875);
FORCEPROP 1 LAST VALUE 0
J 2
(150 -2875);
DISPLAY 0.787234 (150 -2875);
FORCEPROP 1 LAST WATTAGE 1/16W
J 2
(350 -2775);
DISPLAY 0.638298 (350 -2775);
FORCEPROP 1 LAST $LOCATION R2659
J 0
(-375 -2875);
DISPLAY 0.808511 (-375 -2875);
FORCEPROP 1 LASTPIN (-225 -2875) $PN 1
J 0
(-213 -2863);
DISPLAY 0.787234 (-213 -2863);
FORCEPROP 1 LASTPIN (-25 -2875) $PN 2
J 0
(-63 -2863);
DISPLAY 0.787234 (-63 -2863);
FORCEPROP 2 LAST CDS_LIB pure_quanta
J 0
(-125 -2875);
PAINT MONO (-125 -2875);
DISPLAY INVISIBLE (-125 -2875);
FORCEPROP 1 LAST PATH I27
J 0
(-175 -2725);
DISPLAY 0.978723 (-175 -2725);
PAINT WHITE (-175 -2725);
DISPLAY INVISIBLE (-175 -2725);
FORCEPROP 2 LAST CDS_LOCATION R2659
J 0
(-175 -2675);
DISPLAY 1.021277 (-175 -2675);
DISPLAY INVISIBLE (-175 -2675);
FORCEPROP 2 LAST $SEC 1
J 0
(-175 -2675);
DISPLAY 0.680851 (-175 -2675);
PAINT MONO (-175 -2675);
DISPLAY INVISIBLE (-175 -2675);
FORCEPROP 2 LAST CDS_SEC 1
J 0
(-175 -2675);
DISPLAY 1.021277 (-175 -2675);
DISPLAY INVISIBLE (-175 -2675);
FORCEADD Q_RES..1
(-125 -3025);
FORCEPROP 1 LAST PART_NUMBER CS00002JB13
J 0
(0 -2975);
DISPLAY 0.638298 (0 -2975);
DISPLAY INVISIBLE (0 -2975);
FORCEPROP 1 LAST PACK_TYPE 0402LF
J 0
(275 -3025);
DISPLAY 0.787234 (275 -3025);
FORCEPROP 1 LAST WATTAGE 1/16W
J 2
(350 -2925);
DISPLAY 0.638298 (350 -2925);
FORCEPROP 1 LAST MATERIAL CHIP
J 0
(0 -2925);
DISPLAY 0.638298 (0 -2925);
FORCEPROP 1 LAST VALUE 0
J 2
(150 -3025);
DISPLAY 0.787234 (150 -3025);
FORCEPROP 1 LAST TOLERANCE 5%
J 0
(175 -3025);
DISPLAY 0.787234 (175 -3025);
FORCEPROP 1 LAST $LOCATION R2660
J 0
(-375 -3025);
DISPLAY 0.808511 (-375 -3025);
FORCEPROP 1 LASTPIN (-225 -3025) $PN 1
J 0
(-213 -3013);
DISPLAY 0.787234 (-213 -3013);
FORCEPROP 1 LASTPIN (-25 -3025) $PN 2
J 0
(-63 -3013);
DISPLAY 0.787234 (-63 -3013);
FORCEPROP 2 LAST CDS_LIB pure_quanta
J 0
(-125 -3025);
PAINT MONO (-125 -3025);
DISPLAY INVISIBLE (-125 -3025);
FORCEPROP 1 LAST PATH I28
J 0
(-175 -2875);
DISPLAY 0.978723 (-175 -2875);
PAINT WHITE (-175 -2875);
DISPLAY INVISIBLE (-175 -2875);
FORCEPROP 2 LAST CDS_LOCATION R2660
J 0
(-175 -2825);
DISPLAY 1.021277 (-175 -2825);
DISPLAY INVISIBLE (-175 -2825);
FORCEPROP 2 LAST $SEC 1
J 0
(-175 -2825);
DISPLAY 0.680851 (-175 -2825);
PAINT MONO (-175 -2825);
DISPLAY INVISIBLE (-175 -2825);
FORCEPROP 2 LAST CDS_SEC 1
J 0
(-175 -2825);
DISPLAY 1.021277 (-175 -2825);
DISPLAY INVISIBLE (-175 -2825);
FORCEADD OFFPAGE..2
(1750 -7625);
FORCEPROP 2 LAST $XR0 159 
J 0
(1939 -7625);
DISPLAY 0.638298 (1939 -7625);
PAINT MONO (1939 -7625);
FORCEPROP 1 LAST COMMENT_BODY TRUE
J 0
(1705 -7720);
DISPLAY 0.872340 (1705 -7720);
PAINT GREEN (1705 -7720);
DISPLAY INVISIBLE (1705 -7720);
FORCEPROP 1 LAST OFFPAGE TRUE
J 0
(2075 -7750);
DISPLAY 0.872340 (2075 -7750);
DISPLAY INVISIBLE (2075 -7750);
FORCEPROP 2 LAST CDS_LIB standard
J 0
(1750 -7625);
DISPLAY INVISIBLE (1750 -7625);
FORCEPROP 2 LAST PATH I29
J 0
(1950 -7575);
DISPLAY 1.021277 (1950 -7575);
DISPLAY INVISIBLE (1950 -7575);
FORCEADD OFFPAGE..1
(-1525 -7375);
FORCEPROP 2 LAST $XR0 206 
J 0
(-1777 -7375);
DISPLAY 0.638298 (-1777 -7375);
PAINT MONO (-1777 -7375);
FORCEPROP 2 LAST CDS_LIB standard
J 0
(-1525 -7375);
DISPLAY INVISIBLE (-1525 -7375);
FORCEPROP 1 LAST OFFPAGE TRUE
J 0
(-1200 -7500);
DISPLAY 0.872340 (-1200 -7500);
DISPLAY INVISIBLE (-1200 -7500);
FORCEPROP 1 LAST COMMENT_BODY TRUE
J 0
(-1400 -7475);
DISPLAY 0.872340 (-1400 -7475);
PAINT GREEN (-1400 -7475);
DISPLAY INVISIBLE (-1400 -7475);
FORCEPROP 2 LAST PATH I3
J 0
(-1775 -7325);
DISPLAY 1.021277 (-1775 -7325);
DISPLAY INVISIBLE (-1775 -7325);
FORCEADD OFFPAGE..2
(1750 -7775);
FORCEPROP 2 LAST $XR0 159 
J 0
(1939 -7775);
DISPLAY 0.638298 (1939 -7775);
PAINT MONO (1939 -7775);
FORCEPROP 1 LAST COMMENT_BODY TRUE
J 0
(1705 -7870);
DISPLAY 0.872340 (1705 -7870);
PAINT GREEN (1705 -7870);
DISPLAY INVISIBLE (1705 -7870);
FORCEPROP 1 LAST OFFPAGE TRUE
J 0
(2075 -7900);
DISPLAY 0.872340 (2075 -7900);
DISPLAY INVISIBLE (2075 -7900);
FORCEPROP 2 LAST CDS_LIB standard
J 0
(1750 -7775);
DISPLAY INVISIBLE (1750 -7775);
FORCEPROP 2 LAST PATH I30
J 0
(1950 -7725);
DISPLAY 1.021277 (1950 -7725);
DISPLAY INVISIBLE (1950 -7725);
FORCEADD OFFPAGE..2
(1750 -7375);
FORCEPROP 2 LAST $XR0 159 
J 0
(1939 -7375);
DISPLAY 0.638298 (1939 -7375);
PAINT MONO (1939 -7375);
FORCEPROP 1 LAST COMMENT_BODY TRUE
J 0
(1705 -7470);
DISPLAY 0.872340 (1705 -7470);
PAINT GREEN (1705 -7470);
DISPLAY INVISIBLE (1705 -7470);
FORCEPROP 1 LAST OFFPAGE TRUE
J 0
(2075 -7500);
DISPLAY 0.872340 (2075 -7500);
DISPLAY INVISIBLE (2075 -7500);
FORCEPROP 2 LAST CDS_LIB standard
J 0
(1750 -7375);
DISPLAY INVISIBLE (1750 -7375);
FORCEPROP 2 LAST PATH I31
J 0
(1950 -7325);
DISPLAY 1.021277 (1950 -7325);
DISPLAY INVISIBLE (1950 -7325);
FORCEADD OFFPAGE..2
(1750 -7225);
FORCEPROP 2 LAST $XR0 159 
J 0
(1939 -7225);
DISPLAY 0.638298 (1939 -7225);
PAINT MONO (1939 -7225);
FORCEPROP 1 LAST COMMENT_BODY TRUE
J 0
(1705 -7320);
DISPLAY 0.872340 (1705 -7320);
PAINT GREEN (1705 -7320);
DISPLAY INVISIBLE (1705 -7320);
FORCEPROP 1 LAST OFFPAGE TRUE
J 0
(2075 -7350);
DISPLAY 0.872340 (2075 -7350);
DISPLAY INVISIBLE (2075 -7350);
FORCEPROP 2 LAST CDS_LIB standard
J 0
(1750 -7225);
DISPLAY INVISIBLE (1750 -7225);
FORCEPROP 2 LAST PATH I32
J 0
(1950 -7175);
DISPLAY 1.021277 (1950 -7175);
DISPLAY INVISIBLE (1950 -7175);
FORCEADD OFFPAGE..2
(1750 -6975);
FORCEPROP 2 LAST $XR0 159 
J 0
(1939 -6975);
DISPLAY 0.638298 (1939 -6975);
PAINT MONO (1939 -6975);
FORCEPROP 1 LAST COMMENT_BODY TRUE
J 0
(1705 -7070);
DISPLAY 0.872340 (1705 -7070);
PAINT GREEN (1705 -7070);
DISPLAY INVISIBLE (1705 -7070);
FORCEPROP 1 LAST OFFPAGE TRUE
J 0
(2075 -7100);
DISPLAY 0.872340 (2075 -7100);
DISPLAY INVISIBLE (2075 -7100);
FORCEPROP 2 LAST CDS_LIB standard
J 0
(1750 -6975);
DISPLAY INVISIBLE (1750 -6975);
FORCEPROP 2 LAST PATH I33
J 0
(1950 -6925);
DISPLAY 1.021277 (1950 -6925);
DISPLAY INVISIBLE (1950 -6925);
FORCEADD OFFPAGE..2
(1750 -6825);
FORCEPROP 2 LAST $XR0 159 
J 0
(1939 -6825);
DISPLAY 0.638298 (1939 -6825);
PAINT MONO (1939 -6825);
FORCEPROP 1 LAST COMMENT_BODY TRUE
J 0
(1705 -6920);
DISPLAY 0.872340 (1705 -6920);
PAINT GREEN (1705 -6920);
DISPLAY INVISIBLE (1705 -6920);
FORCEPROP 1 LAST OFFPAGE TRUE
J 0
(2075 -6950);
DISPLAY 0.872340 (2075 -6950);
DISPLAY INVISIBLE (2075 -6950);
FORCEPROP 2 LAST CDS_LIB standard
J 0
(1750 -6825);
DISPLAY INVISIBLE (1750 -6825);
FORCEPROP 2 LAST PATH I34
J 0
(1950 -6775);
DISPLAY 1.021277 (1950 -6775);
DISPLAY INVISIBLE (1950 -6775);
FORCEADD OFFPAGE..2
(1750 -6575);
FORCEPROP 2 LAST $XR0 159 
J 0
(1939 -6575);
DISPLAY 0.638298 (1939 -6575);
PAINT MONO (1939 -6575);
FORCEPROP 1 LAST COMMENT_BODY TRUE
J 0
(1705 -6670);
DISPLAY 0.872340 (1705 -6670);
PAINT GREEN (1705 -6670);
DISPLAY INVISIBLE (1705 -6670);
FORCEPROP 1 LAST OFFPAGE TRUE
J 0
(2075 -6700);
DISPLAY 0.872340 (2075 -6700);
DISPLAY INVISIBLE (2075 -6700);
FORCEPROP 2 LAST CDS_LIB standard
J 0
(1750 -6575);
DISPLAY INVISIBLE (1750 -6575);
FORCEPROP 2 LAST PATH I35
J 0
(1950 -6525);
DISPLAY 1.021277 (1950 -6525);
DISPLAY INVISIBLE (1950 -6525);
FORCEADD OFFPAGE..2
(1750 -6425);
FORCEPROP 2 LAST $XR0 159 
J 0
(1939 -6425);
DISPLAY 0.638298 (1939 -6425);
PAINT MONO (1939 -6425);
FORCEPROP 1 LAST COMMENT_BODY TRUE
J 0
(1705 -6520);
DISPLAY 0.872340 (1705 -6520);
PAINT GREEN (1705 -6520);
DISPLAY INVISIBLE (1705 -6520);
FORCEPROP 1 LAST OFFPAGE TRUE
J 0
(2075 -6550);
DISPLAY 0.872340 (2075 -6550);
DISPLAY INVISIBLE (2075 -6550);
FORCEPROP 2 LAST CDS_LIB standard
J 0
(1750 -6425);
DISPLAY INVISIBLE (1750 -6425);
FORCEPROP 2 LAST PATH I36
J 0
(1950 -6375);
DISPLAY 1.021277 (1950 -6375);
DISPLAY INVISIBLE (1950 -6375);
FORCEADD OFFPAGE..2
(1700 -3875);
FORCEPROP 2 LAST $XR0 143 
J 0
(1889 -3875);
DISPLAY 0.638298 (1889 -3875);
PAINT MONO (1889 -3875);
FORCEPROP 1 LAST COMMENT_BODY TRUE
J 0
(1655 -3970);
DISPLAY 0.872340 (1655 -3970);
PAINT GREEN (1655 -3970);
DISPLAY INVISIBLE (1655 -3970);
FORCEPROP 1 LAST OFFPAGE TRUE
J 0
(2025 -4000);
DISPLAY 0.872340 (2025 -4000);
DISPLAY INVISIBLE (2025 -4000);
FORCEPROP 2 LAST CDS_LIB standard
J 0
(1700 -3875);
DISPLAY INVISIBLE (1700 -3875);
FORCEPROP 2 LAST PATH I37
J 0
(1900 -3825);
DISPLAY 1.021277 (1900 -3825);
DISPLAY INVISIBLE (1900 -3825);
FORCEADD OFFPAGE..2
(1700 -3725);
FORCEPROP 2 LAST $XR0 143 
J 0
(1889 -3725);
DISPLAY 0.638298 (1889 -3725);
PAINT MONO (1889 -3725);
FORCEPROP 1 LAST COMMENT_BODY TRUE
J 0
(1655 -3820);
DISPLAY 0.872340 (1655 -3820);
PAINT GREEN (1655 -3820);
DISPLAY INVISIBLE (1655 -3820);
FORCEPROP 1 LAST OFFPAGE TRUE
J 0
(2025 -3850);
DISPLAY 0.872340 (2025 -3850);
DISPLAY INVISIBLE (2025 -3850);
FORCEPROP 2 LAST CDS_LIB standard
J 0
(1700 -3725);
DISPLAY INVISIBLE (1700 -3725);
FORCEPROP 2 LAST PATH I38
J 0
(1900 -3675);
DISPLAY 1.021277 (1900 -3675);
DISPLAY INVISIBLE (1900 -3675);
FORCEADD OFFPAGE..2
(1700 -3500);
FORCEPROP 2 LAST $XR0 143 
J 0
(1889 -3500);
DISPLAY 0.638298 (1889 -3500);
PAINT MONO (1889 -3500);
FORCEPROP 2 LAST CDS_LIB standard
J 0
(1700 -3500);
DISPLAY INVISIBLE (1700 -3500);
FORCEPROP 1 LAST OFFPAGE TRUE
J 0
(2025 -3625);
DISPLAY 0.872340 (2025 -3625);
DISPLAY INVISIBLE (2025 -3625);
FORCEPROP 1 LAST COMMENT_BODY TRUE
J 0
(1655 -3595);
DISPLAY 0.872340 (1655 -3595);
PAINT GREEN (1655 -3595);
DISPLAY INVISIBLE (1655 -3595);
FORCEPROP 2 LAST PATH I39
J 0
(1900 -3450);
DISPLAY 1.021277 (1900 -3450);
DISPLAY INVISIBLE (1900 -3450);
FORCEADD OFFPAGE..1
(-1525 -7225);
FORCEPROP 2 LAST $XR0 206 
J 0
(-1777 -7225);
DISPLAY 0.638298 (-1777 -7225);
PAINT MONO (-1777 -7225);
FORCEPROP 2 LAST CDS_LIB standard
J 0
(-1525 -7225);
DISPLAY INVISIBLE (-1525 -7225);
FORCEPROP 1 LAST OFFPAGE TRUE
J 0
(-1200 -7350);
DISPLAY 0.872340 (-1200 -7350);
DISPLAY INVISIBLE (-1200 -7350);
FORCEPROP 1 LAST COMMENT_BODY TRUE
J 0
(-1400 -7325);
DISPLAY 0.872340 (-1400 -7325);
PAINT GREEN (-1400 -7325);
DISPLAY INVISIBLE (-1400 -7325);
FORCEPROP 2 LAST PATH I4
J 0
(-1775 -7175);
DISPLAY 1.021277 (-1775 -7175);
DISPLAY INVISIBLE (-1775 -7175);
FORCEADD OFFPAGE..2
(1700 -3350);
FORCEPROP 2 LAST $XR0 143 
J 0
(1889 -3350);
DISPLAY 0.638298 (1889 -3350);
PAINT MONO (1889 -3350);
FORCEPROP 2 LAST CDS_LIB standard
J 0
(1700 -3350);
DISPLAY INVISIBLE (1700 -3350);
FORCEPROP 1 LAST OFFPAGE TRUE
J 0
(2025 -3475);
DISPLAY 0.872340 (2025 -3475);
DISPLAY INVISIBLE (2025 -3475);
FORCEPROP 1 LAST COMMENT_BODY TRUE
J 0
(1655 -3445);
DISPLAY 0.872340 (1655 -3445);
PAINT GREEN (1655 -3445);
DISPLAY INVISIBLE (1655 -3445);
FORCEPROP 2 LAST PATH I40
J 0
(1900 -3300);
DISPLAY 1.021277 (1900 -3300);
DISPLAY INVISIBLE (1900 -3300);
FORCEADD OFFPAGE..2
(1725 -3025);
FORCEPROP 2 LAST $XR0 143 
J 0
(1914 -3025);
DISPLAY 0.638298 (1914 -3025);
PAINT MONO (1914 -3025);
FORCEPROP 2 LAST CDS_LIB standard
J 0
(1725 -3025);
DISPLAY INVISIBLE (1725 -3025);
FORCEPROP 1 LAST OFFPAGE TRUE
J 0
(2050 -3150);
DISPLAY 0.872340 (2050 -3150);
DISPLAY INVISIBLE (2050 -3150);
FORCEPROP 1 LAST COMMENT_BODY TRUE
J 0
(1680 -3120);
DISPLAY 0.872340 (1680 -3120);
PAINT GREEN (1680 -3120);
DISPLAY INVISIBLE (1680 -3120);
FORCEPROP 2 LAST PATH I41
J 0
(1925 -2975);
DISPLAY 1.021277 (1925 -2975);
DISPLAY INVISIBLE (1925 -2975);
FORCEADD OFFPAGE..2
(1725 -2875);
FORCEPROP 2 LAST $XR0 143 
J 0
(1914 -2875);
DISPLAY 0.638298 (1914 -2875);
PAINT MONO (1914 -2875);
FORCEPROP 2 LAST CDS_LIB standard
J 0
(1725 -2875);
DISPLAY INVISIBLE (1725 -2875);
FORCEPROP 1 LAST OFFPAGE TRUE
J 0
(2050 -3000);
DISPLAY 0.872340 (2050 -3000);
DISPLAY INVISIBLE (2050 -3000);
FORCEPROP 1 LAST COMMENT_BODY TRUE
J 0
(1680 -2970);
DISPLAY 0.872340 (1680 -2970);
PAINT GREEN (1680 -2970);
DISPLAY INVISIBLE (1680 -2970);
FORCEPROP 2 LAST PATH I42
J 0
(1925 -2825);
DISPLAY 1.021277 (1925 -2825);
DISPLAY INVISIBLE (1925 -2825);
FORCEADD OFFPAGE..1
(-1525 -6975);
FORCEPROP 2 LAST $XR0 206 
J 0
(-1777 -6975);
DISPLAY 0.638298 (-1777 -6975);
PAINT MONO (-1777 -6975);
FORCEPROP 2 LAST CDS_LIB standard
J 0
(-1525 -6975);
DISPLAY INVISIBLE (-1525 -6975);
FORCEPROP 1 LAST OFFPAGE TRUE
J 0
(-1200 -7100);
DISPLAY 0.872340 (-1200 -7100);
DISPLAY INVISIBLE (-1200 -7100);
FORCEPROP 1 LAST COMMENT_BODY TRUE
J 0
(-1400 -7075);
DISPLAY 0.872340 (-1400 -7075);
PAINT GREEN (-1400 -7075);
DISPLAY INVISIBLE (-1400 -7075);
FORCEPROP 2 LAST PATH I5
J 0
(-1775 -6925);
DISPLAY 1.021277 (-1775 -6925);
DISPLAY INVISIBLE (-1775 -6925);
FORCEADD OFFPAGE..1
(-1525 -6825);
FORCEPROP 2 LAST $XR0 206 
J 0
(-1777 -6825);
DISPLAY 0.638298 (-1777 -6825);
PAINT MONO (-1777 -6825);
FORCEPROP 2 LAST CDS_LIB standard
J 0
(-1525 -6825);
DISPLAY INVISIBLE (-1525 -6825);
FORCEPROP 1 LAST OFFPAGE TRUE
J 0
(-1200 -6950);
DISPLAY 0.872340 (-1200 -6950);
DISPLAY INVISIBLE (-1200 -6950);
FORCEPROP 1 LAST COMMENT_BODY TRUE
J 0
(-1400 -6925);
DISPLAY 0.872340 (-1400 -6925);
PAINT GREEN (-1400 -6925);
DISPLAY INVISIBLE (-1400 -6925);
FORCEPROP 2 LAST PATH I6
J 0
(-1775 -6775);
DISPLAY 1.021277 (-1775 -6775);
DISPLAY INVISIBLE (-1775 -6775);
FORCEADD OFFPAGE..1
(-1525 -6575);
FORCEPROP 2 LAST $XR0 206 
J 0
(-1777 -6575);
DISPLAY 0.638298 (-1777 -6575);
PAINT MONO (-1777 -6575);
FORCEPROP 2 LAST CDS_LIB standard
J 0
(-1525 -6575);
DISPLAY INVISIBLE (-1525 -6575);
FORCEPROP 1 LAST OFFPAGE TRUE
J 0
(-1200 -6700);
DISPLAY 0.872340 (-1200 -6700);
DISPLAY INVISIBLE (-1200 -6700);
FORCEPROP 1 LAST COMMENT_BODY TRUE
J 0
(-1400 -6675);
DISPLAY 0.872340 (-1400 -6675);
PAINT GREEN (-1400 -6675);
DISPLAY INVISIBLE (-1400 -6675);
FORCEPROP 2 LAST PATH I7
J 0
(-1775 -6525);
DISPLAY 1.021277 (-1775 -6525);
DISPLAY INVISIBLE (-1775 -6525);
FORCEADD OFFPAGE..1
(-1525 -6425);
FORCEPROP 2 LAST $XR0 206 
J 0
(-1777 -6425);
DISPLAY 0.638298 (-1777 -6425);
PAINT MONO (-1777 -6425);
FORCEPROP 2 LAST CDS_LIB standard
J 0
(-1525 -6425);
DISPLAY INVISIBLE (-1525 -6425);
FORCEPROP 1 LAST OFFPAGE TRUE
J 0
(-1200 -6550);
DISPLAY 0.872340 (-1200 -6550);
DISPLAY INVISIBLE (-1200 -6550);
FORCEPROP 1 LAST COMMENT_BODY TRUE
J 0
(-1400 -6525);
DISPLAY 0.872340 (-1400 -6525);
PAINT GREEN (-1400 -6525);
DISPLAY INVISIBLE (-1400 -6525);
FORCEPROP 2 LAST PATH I8
J 0
(-1775 -6375);
DISPLAY 1.021277 (-1775 -6375);
DISPLAY INVISIBLE (-1775 -6375);
FORCEADD OFFPAGE..1
(-1575 -3875);
FORCEPROP 2 LAST $XR0 211 
J 0
(-1827 -3875);
DISPLAY 0.638298 (-1827 -3875);
PAINT MONO (-1827 -3875);
FORCEPROP 1 LAST COMMENT_BODY TRUE
J 0
(-1450 -3975);
DISPLAY 0.872340 (-1450 -3975);
PAINT GREEN (-1450 -3975);
DISPLAY INVISIBLE (-1450 -3975);
FORCEPROP 1 LAST OFFPAGE TRUE
J 0
(-1250 -4000);
DISPLAY 0.872340 (-1250 -4000);
DISPLAY INVISIBLE (-1250 -4000);
FORCEPROP 2 LAST CDS_LIB standard
J 0
(-1575 -3875);
DISPLAY INVISIBLE (-1575 -3875);
FORCEPROP 2 LAST PATH I9
J 0
(-1825 -3825);
DISPLAY 1.021277 (-1825 -3825);
DISPLAY INVISIBLE (-1825 -3825);
FORCEADD QUANTA_TITLE_BLOCK_C..1
(6425 -8475);
FORCEPROP 0 LAST CDS_CON_LAST_MODIFIED Fri Aug 25 14:03:23 2023
J 0
(4540 -8460);
PAINT MONO (4540 -8460);
DISPLAY INVISIBLE (4540 -8460);
FORCEPROP 2 LAST CUSTOM_TXT_CDS <XR_PAGE_TITLE>
J 0
(-1465 -3225);
DISPLAY 0.638298 (-1465 -3225);
PAINT PINK (-1465 -3225);
DISPLAY INVISIBLE (-1465 -3225);
FORCEPROP 2 LAST CUSTOM_TXT_CDS <Q_REV>
J 0
(6241 -8372);
DISPLAY 1.212766 (6241 -8372);
FORCEPROP 2 LAST CUSTOM_TXT_CDS <Q_NUMBER>
J 0
(5022 -8372);
DISPLAY 1.212766 (5022 -8372);
FORCEPROP 2 LAST CUSTOM_TXT_CDS <CON_PAGE_NUM> OF <CON_TOTAL_PAGES>
J 0
(5979 -8457);
DISPLAY 0.978723 (5979 -8457);
FORCEPROP 2 LAST CUSTOM_TXT_CDS <NAME_2>
J 0
(3250 -8425);
FORCEPROP 2 LAST CUSTOM_TXT_CDS <NAME_1>
J 0
(3250 -8300);
FORCEPROP 2 LAST CUSTOM_TXT_CDS <Q_PROJ>
J 0
(4043 -8373);
DISPLAY 1.212766 (4043 -8373);
FORCEPROP 2 LAST CUSTOM_TXT_CDS <CON_LAST_MODIFIED>
J 0
(4540 -8460);
DISPLAY 0.978723 (4540 -8460);
FORCEPROP 1 LAST Q_TITLE CLK- DB2000QL CLK BUFFER (2/2)
J 0
(-2916 -8449);
DISPLAY 1.957447 (-2916 -8449);
PAINT GREEN (-2916 -8449);
FORCEPROP 1 LAST Q_DEPT 
J 1
(2662 -8426);
DISPLAY 1.957447 (2662 -8426);
PAINT GREEN (2662 -8426);
FORCEPROP 2 LAST PAGE_BORDER TRUE
J 0
(-1465 -3225);
DISPLAY 0.638298 (-1465 -3225);
PAINT PINK (-1465 -3225);
DISPLAY INVISIBLE (-1465 -3225);
FORCEPROP 1 LAST CDS_LMAN_SYM_OUTLINE -9475,6775,100,-125
J 0
(6425 -8475);
DISPLAY 0.468085 (6425 -8475);
PAINT GREEN (6425 -8475);
DISPLAY INVISIBLE (6425 -8475);
FORCEPROP 2 LAST CDS_LIB pure_quanta
J 0
(6425 -8475);
PAINT MONO (6425 -8475);
DISPLAY INVISIBLE (6425 -8475);
FORCEPROP 1 LAST COMMENT_BODY TRUE
J 0
(6437 -8488);
DISPLAY 0.978723 (6437 -8488);
PAINT GREEN (6437 -8488);
DISPLAY INVISIBLE (6437 -8488);
FORCEPROP 2 LAST CDS_XR_PAGE_TITLE CR-207 : @S9S_MB_2U_LIB.S9S_MB_2U(SCH_1):PAGE207
J 0
(-1465 -3225);
DISPLAY 0.638298 (-1465 -3225);
PAINT PINK (-1465 -3225);
DISPLAY INVISIBLE (-1465 -3225);
WIRE 16 -1 (-50 -3725)(1650 -3725);
FORCEPROP 0 LAST CDS_PHYS_NET_NAME CLK_100M_GPU_2_DP
J 0
(640 -3683);
PAINT MONO (640 -3683);
DISPLAY INVISIBLE (640 -3683);
FORCEPROP 2 LAST SIG_NAME CLK_100M_GPU_2_DP
J 0
(665 -3715);
DISPLAY 0.680851 (665 -3715);
PAINT WHITE (665 -3715);
WIRE 16 -1 (-50 -3350)(1650 -3350);
FORCEPROP 0 LAST CDS_PHYS_NET_NAME CLK_100M_GPU_1_DP
J 0
(640 -3308);
PAINT MONO (640 -3308);
DISPLAY INVISIBLE (640 -3308);
FORCEPROP 2 LAST SIG_NAME CLK_100M_GPU_1_DP
J 0
(665 -3340);
DISPLAY 0.680851 (665 -3340);
PAINT WHITE (665 -3340);
WIRE 16 -1 (-50 -3500)(1650 -3500);
FORCEPROP 0 LAST CDS_PHYS_NET_NAME CLK_100M_GPU_1_DN
J 0
(640 -3458);
PAINT MONO (640 -3458);
DISPLAY INVISIBLE (640 -3458);
FORCEPROP 2 LAST SIG_NAME CLK_100M_GPU_1_DN
J 0
(665 -3490);
DISPLAY 0.680851 (665 -3490);
PAINT WHITE (665 -3490);
WIRE 16 -1 (-50 -3875)(1650 -3875);
FORCEPROP 0 LAST CDS_PHYS_NET_NAME CLK_100M_GPU_2_DN
J 0
(640 -3833);
PAINT MONO (640 -3833);
DISPLAY INVISIBLE (640 -3833);
FORCEPROP 2 LAST SIG_NAME CLK_100M_GPU_2_DN
J 0
(665 -3865);
DISPLAY 0.680851 (665 -3865);
PAINT WHITE (665 -3865);
WIRE 16 -1 (-25 -3025)(1675 -3025);
FORCEPROP 0 LAST CDS_PHYS_NET_NAME CLK_100M_SWB_DN
J 0
(665 -2983);
PAINT MONO (665 -2983);
DISPLAY INVISIBLE (665 -2983);
FORCEPROP 2 LAST SIG_NAME CLK_100M_SWB_DN
J 0
(690 -3015);
DISPLAY 0.680851 (690 -3015);
PAINT WHITE (690 -3015);
WIRE 16 -1 (-25 -2875)(1675 -2875);
FORCEPROP 0 LAST CDS_PHYS_NET_NAME CLK_100M_SWB_DP
J 0
(665 -2833);
PAINT MONO (665 -2833);
DISPLAY INVISIBLE (665 -2833);
FORCEPROP 2 LAST SIG_NAME CLK_100M_SWB_DP
J 0
(690 -2865);
DISPLAY 0.680851 (690 -2865);
PAINT WHITE (690 -2865);
WIRE 16 -1 (0 -6975)(1700 -6975);
FORCEPROP 0 LAST CDS_PHYS_NET_NAME CLK_100M_OCP_V3_2_B_DN
J 0
(690 -6933);
PAINT MONO (690 -6933);
DISPLAY INVISIBLE (690 -6933);
FORCEPROP 2 LAST SIG_NAME CLK_100M_OCP_V3_2_B_DN
J 0
(790 -6965);
DISPLAY 0.680851 (790 -6965);
PAINT WHITE (790 -6965);
WIRE 16 -1 (0 -6425)(1700 -6425);
FORCEPROP 0 LAST CDS_PHYS_NET_NAME CLK_100M_OCP_V3_2_A_DP
J 0
(690 -6383);
PAINT MONO (690 -6383);
DISPLAY INVISIBLE (690 -6383);
FORCEPROP 2 LAST SIG_NAME CLK_100M_OCP_V3_2_A_DP
J 0
(790 -6415);
DISPLAY 0.680851 (790 -6415);
PAINT WHITE (790 -6415);
WIRE 16 -1 (0 -6825)(1700 -6825);
FORCEPROP 0 LAST CDS_PHYS_NET_NAME CLK_100M_OCP_V3_2_B_DP
J 0
(690 -6783);
PAINT MONO (690 -6783);
DISPLAY INVISIBLE (690 -6783);
FORCEPROP 2 LAST SIG_NAME CLK_100M_OCP_V3_2_B_DP
J 0
(790 -6815);
DISPLAY 0.680851 (790 -6815);
PAINT WHITE (790 -6815);
WIRE 16 -1 (0 -6575)(1700 -6575);
FORCEPROP 0 LAST CDS_PHYS_NET_NAME CLK_100M_OCP_V3_2_A_DN
J 0
(690 -6533);
PAINT MONO (690 -6533);
DISPLAY INVISIBLE (690 -6533);
FORCEPROP 2 LAST SIG_NAME CLK_100M_OCP_V3_2_A_DN
J 0
(790 -6565);
DISPLAY 0.680851 (790 -6565);
PAINT WHITE (790 -6565);
WIRE 16 -1 (0 -7225)(1700 -7225);
FORCEPROP 0 LAST CDS_PHYS_NET_NAME CLK_100M_OCP_V3_2_C_DP
J 0
(690 -7183);
PAINT MONO (690 -7183);
DISPLAY INVISIBLE (690 -7183);
FORCEPROP 2 LAST SIG_NAME CLK_100M_OCP_V3_2_C_DP
J 0
(790 -7215);
DISPLAY 0.680851 (790 -7215);
PAINT WHITE (790 -7215);
WIRE 16 -1 (0 -7375)(1700 -7375);
FORCEPROP 0 LAST CDS_PHYS_NET_NAME CLK_100M_OCP_V3_2_C_DN
J 0
(690 -7333);
PAINT MONO (690 -7333);
DISPLAY INVISIBLE (690 -7333);
FORCEPROP 2 LAST SIG_NAME CLK_100M_OCP_V3_2_C_DN
J 0
(790 -7365);
DISPLAY 0.680851 (790 -7365);
PAINT WHITE (790 -7365);
WIRE 16 -1 (0 -7625)(1700 -7625);
FORCEPROP 0 LAST CDS_PHYS_NET_NAME CLK_100M_OCP_V3_2_D_DP
J 0
(690 -7583);
PAINT MONO (690 -7583);
DISPLAY INVISIBLE (690 -7583);
FORCEPROP 2 LAST SIG_NAME CLK_100M_OCP_V3_2_D_DP
J 0
(790 -7615);
DISPLAY 0.680851 (790 -7615);
PAINT WHITE (790 -7615);
WIRE 16 -1 (0 -7775)(1700 -7775);
FORCEPROP 0 LAST CDS_PHYS_NET_NAME CLK_100M_OCP_V3_2_D_DN
J 0
(690 -7733);
PAINT MONO (690 -7733);
DISPLAY INVISIBLE (690 -7733);
FORCEPROP 2 LAST SIG_NAME CLK_100M_OCP_V3_2_D_DN
J 0
(790 -7765);
DISPLAY 0.680851 (790 -7765);
PAINT WHITE (790 -7765);
WIRE 16 -1 (-250 -3350)(-1525 -3350);
FORCEPROP 0 LAST CDS_PHYS_NET_NAME CLK_100M_GPU_1_R_DP
J 0
(-1360 -3308);
PAINT MONO (-1360 -3308);
DISPLAY INVISIBLE (-1360 -3308);
FORCEPROP 2 LAST SIG_NAME CLK_100M_GPU_1_R_DP
J 0
(-1335 -3340);
DISPLAY 0.680851 (-1335 -3340);
PAINT WHITE (-1335 -3340);
WIRE 16 -1 (-250 -3725)(-1525 -3725);
FORCEPROP 0 LAST CDS_PHYS_NET_NAME CLK_100M_GPU_2_R_DP
J 0
(-1360 -3683);
PAINT MONO (-1360 -3683);
DISPLAY INVISIBLE (-1360 -3683);
FORCEPROP 2 LAST SIG_NAME CLK_100M_GPU_2_R_DP
J 0
(-1335 -3715);
DISPLAY 0.680851 (-1335 -3715);
PAINT WHITE (-1335 -3715);
WIRE 16 -1 (-250 -3500)(-1525 -3500);
FORCEPROP 0 LAST CDS_PHYS_NET_NAME CLK_100M_GPU_1_R_DN
J 0
(-1360 -3458);
PAINT MONO (-1360 -3458);
DISPLAY INVISIBLE (-1360 -3458);
FORCEPROP 2 LAST SIG_NAME CLK_100M_GPU_1_R_DN
J 0
(-1335 -3490);
DISPLAY 0.680851 (-1335 -3490);
PAINT WHITE (-1335 -3490);
WIRE 16 -1 (-225 -3025)(-1500 -3025);
FORCEPROP 0 LAST CDS_PHYS_NET_NAME CLK_100M_SWB_R_DN
J 0
(-1335 -2983);
PAINT MONO (-1335 -2983);
DISPLAY INVISIBLE (-1335 -2983);
FORCEPROP 2 LAST SIG_NAME CLK_100M_SWB_R_DN
J 0
(-1310 -3015);
DISPLAY 0.680851 (-1310 -3015);
PAINT WHITE (-1310 -3015);
WIRE 16 -1 (-225 -2875)(-1500 -2875);
FORCEPROP 0 LAST CDS_PHYS_NET_NAME CLK_100M_SWB_R_DP
J 0
(-1335 -2833);
PAINT MONO (-1335 -2833);
DISPLAY INVISIBLE (-1335 -2833);
FORCEPROP 2 LAST SIG_NAME CLK_100M_SWB_R_DP
J 0
(-1310 -2865);
DISPLAY 0.680851 (-1310 -2865);
PAINT WHITE (-1310 -2865);
WIRE 16 -1 (-200 -7775)(-1475 -7775);
FORCEPROP 0 LAST CDS_PHYS_NET_NAME CLK_100M_OCP_V3_2_D_R_DN
J 0
(-1310 -7733);
PAINT MONO (-1310 -7733);
DISPLAY INVISIBLE (-1310 -7733);
FORCEPROP 2 LAST SIG_NAME CLK_100M_OCP_V3_2_D_R_DN
J 0
(-1285 -7765);
DISPLAY 0.680851 (-1285 -7765);
PAINT WHITE (-1285 -7765);
WIRE 16 -1 (-200 -6425)(-1475 -6425);
FORCEPROP 0 LAST CDS_PHYS_NET_NAME CLK_100M_OCP_V3_2_A_R_DP
J 0
(-1310 -6383);
PAINT MONO (-1310 -6383);
DISPLAY INVISIBLE (-1310 -6383);
FORCEPROP 2 LAST SIG_NAME CLK_100M_OCP_V3_2_A_R_DP
J 0
(-1285 -6415);
DISPLAY 0.680851 (-1285 -6415);
PAINT WHITE (-1285 -6415);
WIRE 16 -1 (-200 -7625)(-1475 -7625);
FORCEPROP 0 LAST CDS_PHYS_NET_NAME CLK_100M_OCP_V3_2_D_R_DP
J 0
(-1310 -7583);
PAINT MONO (-1310 -7583);
DISPLAY INVISIBLE (-1310 -7583);
FORCEPROP 2 LAST SIG_NAME CLK_100M_OCP_V3_2_D_R_DP
J 0
(-1285 -7615);
DISPLAY 0.680851 (-1285 -7615);
PAINT WHITE (-1285 -7615);
WIRE 16 -1 (-200 -6575)(-1475 -6575);
FORCEPROP 0 LAST CDS_PHYS_NET_NAME CLK_100M_OCP_V3_2_A_R_DN
J 0
(-1310 -6533);
PAINT MONO (-1310 -6533);
DISPLAY INVISIBLE (-1310 -6533);
FORCEPROP 2 LAST SIG_NAME CLK_100M_OCP_V3_2_A_R_DN
J 0
(-1285 -6565);
DISPLAY 0.680851 (-1285 -6565);
PAINT WHITE (-1285 -6565);
WIRE 16 -1 (-200 -7375)(-1475 -7375);
FORCEPROP 0 LAST CDS_PHYS_NET_NAME CLK_100M_OCP_V3_2_C_R_DN
J 0
(-1310 -7333);
PAINT MONO (-1310 -7333);
DISPLAY INVISIBLE (-1310 -7333);
FORCEPROP 2 LAST SIG_NAME CLK_100M_OCP_V3_2_C_R_DN
J 0
(-1285 -7365);
DISPLAY 0.680851 (-1285 -7365);
PAINT WHITE (-1285 -7365);
WIRE 16 -1 (-200 -7225)(-1475 -7225);
FORCEPROP 0 LAST CDS_PHYS_NET_NAME CLK_100M_OCP_V3_2_C_R_DP
J 0
(-1310 -7183);
PAINT MONO (-1310 -7183);
DISPLAY INVISIBLE (-1310 -7183);
FORCEPROP 2 LAST SIG_NAME CLK_100M_OCP_V3_2_C_R_DP
J 0
(-1285 -7215);
DISPLAY 0.680851 (-1285 -7215);
PAINT WHITE (-1285 -7215);
WIRE 16 -1 (-200 -6975)(-1475 -6975);
FORCEPROP 0 LAST CDS_PHYS_NET_NAME CLK_100M_OCP_V3_2_B_R_DN
J 0
(-1310 -6933);
PAINT MONO (-1310 -6933);
DISPLAY INVISIBLE (-1310 -6933);
FORCEPROP 2 LAST SIG_NAME CLK_100M_OCP_V3_2_B_R_DN
J 0
(-1285 -6965);
DISPLAY 0.680851 (-1285 -6965);
PAINT WHITE (-1285 -6965);
WIRE 16 -1 (-200 -6825)(-1475 -6825);
FORCEPROP 0 LAST CDS_PHYS_NET_NAME CLK_100M_OCP_V3_2_B_R_DP
J 0
(-1310 -6783);
PAINT MONO (-1310 -6783);
DISPLAY INVISIBLE (-1310 -6783);
FORCEPROP 2 LAST SIG_NAME CLK_100M_OCP_V3_2_B_R_DP
J 0
(-1285 -6815);
DISPLAY 0.680851 (-1285 -6815);
PAINT WHITE (-1285 -6815);
WIRE 16 -1 (-250 -3875)(-1525 -3875);
FORCEPROP 0 LAST CDS_PHYS_NET_NAME CLK_100M_GPU_2_R_DN
J 0
(-1360 -3833);
PAINT MONO (-1360 -3833);
DISPLAY INVISIBLE (-1360 -3833);
FORCEPROP 2 LAST SIG_NAME CLK_100M_GPU_2_R_DN
J 0
(-1335 -3865);
DISPLAY 0.680851 (-1335 -3865);
PAINT WHITE (-1335 -3865);
WIRE 16 2175 (-425 -6300)(525 -6300);
WIRE 16 2175 (525 -6300)(525 -7875);
WIRE 16 2175 (-425 -6300)(-425 -7875);
WIRE 16 2175 (-425 -7875)(525 -7875);
FORCENOTE
20221215 CHANGE R3194,R3195,R3196,R3197,R3198,R3199,R3200,R3202 TO 22 OHM
(-1275 -7975) 0;
DISPLAY LEFT (-1275 -7975);
DISPLAY 1.063830 (-1275 -7975);
PAINT WHITE (-1275 -7975);
FORCENOTE
20210602 MODIFY FOR GT
(400 -2275) 0;
DISPLAY LEFT (400 -2275);
DISPLAY 2.510638 (400 -2275);
PAINT PINK (400 -2275);
FORCENOTE
GPU
(1550 -3250) 0;
DISPLAY LEFT (1550 -3250);
DISPLAY 2.000000 (1550 -3250);
PAINT SKYBLUE (1550 -3250);
FORCENOTE
SWB
(1575 -2775) 0;
DISPLAY LEFT (1575 -2775);
DISPLAY 2.000000 (1575 -2775);
PAINT SKYBLUE (1575 -2775);
QUIT
